# Stackup_F0T_Management_Board_12L_1p6mm_IT-170GRA1_RG311_Rev0p2_20220715 的複本.xls — Manufacuring violation (pcb-stackup)
| Description | Quanta layout design rule | The stackup design rule |  |
| Min. Innerlayer Line Width, 0.5 oz copper (mil) | 3 | 3.29 | Normal |
| Min. Innerlayer Space, 0.5 oz copper (mil) | 3.5 | 4 | Medium |
| Min. Innerlayer Line Width,   1 oz copper (mil) | 4 | NA | High |
| Min. Innerlayer Space, 1 oz copper (mil) | 4 | NA |  |
| Min. Innerlayer Line Width,   2oz copper (mil) | 6 | NA |  |
| Min. Innerlayer Space,  2oz copper (mil) | 6 | NA |  |
| Min. Outerlayer line width, 0.5oz copper foil (mil) | 3.5 | 3.29 |  |
| Min. Outerlayer Space, 0.5oz copper foil (mil) | 3.5 | 4 |  |
| Min. Inner Core/PP thickness (mil) | 3 | 3 |  |
| Max. Aspect Ratio for min. DHS | 12.24 | 6.43 |  |
